FILE_TYPE = MACRO_DRAWING;
SET COLOR_WIRE YELLOW;
SET COLOR_PROP ORANGE;
SET COLOR_DOT WHITE;
SET COLOR_ARC YELLOW;
SET COLOR_BODY GREEN;
SET COLOR_NOTE PURPLE;
SET PROP_DISPLAY VALUE;
SET PAGE_NUMBER P202;
FORCEADD QUANTA_TITLE_BLOCK_C..1
(0 0);
FORCEPROP 1 LAST CUSTOM_TXT_CDS <NAME_2>
J 0
(-3175 50);
FORCEPROP 1 LAST CUSTOM_TXT_CDS <NAME_1>
J 0
(-3175 175);
FORCEPROP 1 LAST CUSTOM_TXT_CDS <Q_NUMBER>
J 0
(-1403 103);
DISPLAY 1.212766 (-1403 103);
FORCEPROP 1 LAST CUSTOM_TXT_CDS <Q_PROJ>
J 0
(-2382 102);
DISPLAY 1.212766 (-2382 102);
FORCEPROP 1 LAST CUSTOM_TXT_CDS <Q_REV>
J 0
(-184 103);
DISPLAY 1.212766 (-184 103);
FORCEPROP 1 LAST CUSTOM_TXT_CDS <CON_LAST_MODIFIED>
J 0
(-1885 15);
DISPLAY 0.978723 (-1885 15);
FORCEPROP 1 LAST CUSTOM_TXT_CDS <CON_PAGE_NUM> OF <CON_TOTAL_PAGES>
J 0
(-446 18);
DISPLAY 0.978723 (-446 18);
FORCEPROP 1 LAST Q_TITLE Blank
J 0
(-9366 26);
DISPLAY 2.446809 (-9366 26);
PAINT GREEN (-9366 26);
FORCEPROP 2 LAST PAGE_BORDER TRUE
J 0
(-7890 5250);
DISPLAY 0.638298 (-7890 5250);
PAINT PINK (-7890 5250);
DISPLAY INVISIBLE (-7890 5250);
FORCEPROP 1 LAST CDS_LMAN_SYM_OUTLINE -9475,6775,100,-125
J 0
(0 0);
DISPLAY 0.468085 (0 0);
PAINT GREEN (0 0);
DISPLAY INVISIBLE (0 0);
FORCEPROP 2 LAST CDS_LIB pure_quanta
J 0
(0 0);
DISPLAY INVISIBLE (0 0);
FORCEPROP 2 LAST CDS_XR_PAGE_TITLE CR-227 : @T6G_MB_LIB.T6G(SCH_1):PAGE227
J 0
(-7890 5250);
DISPLAY 0.638298 (-7890 5250);
PAINT PINK (-7890 5250);
DISPLAY INVISIBLE (-7890 5250);
FORCEPROP 2 LAST CUSTOM_TXT_CDS <XR_PAGE_TITLE>
J 0
(-7890 5250);
DISPLAY 0.638298 (-7890 5250);
PAINT PINK (-7890 5250);
DISPLAY INVISIBLE (-7890 5250);
FORCEPROP 1 LAST COMMENT_BODY TRUE
J 0
(12 -13);
DISPLAY 0.978723 (12 -13);
PAINT GREEN (12 -13);
DISPLAY INVISIBLE (12 -13);
FORCEPROP 1 LAST Q_DEPT BU9
J 1
(-3763 49);
DISPLAY 1.957447 (-3763 49);
PAINT GREEN (-3763 49);
DISPLAY INVISIBLE (-3763 49);
FORCEPROP 0 LAST CDS_CON_LAST_MODIFIED Thu Aug 24 10:15:28 2023
J 0
(-1885 15);
DISPLAY INVISIBLE (-1885 15);
QUIT
